(kicad_pcb
	(version 20260206)
	(generator "pcbnew")
	(generator_version "10.0")
	(general
		(thickness 1.6)
		(legacy_teardrops no)
	)
	(paper "A4")
	(title_block
		(title "pdpb — Lightning_PDPB_BRD.brd")
		(comment 1 "Lightning (Wiwynn / Facebook NVMe JBOF) / footprints 822-828 of 1140")
	)
	(layers
		(0 "F.Cu" signal "TOP")
		(4 "In1.Cu" signal "L2GND")
		(6 "In2.Cu" signal "L3")
		(8 "In3.Cu" signal "L4VCC")
		(10 "In4.Cu" signal "L5VCC")
		(12 "In5.Cu" signal "L6")
		(14 "In6.Cu" signal "L7GND")
		(2 "B.Cu" signal "BOTTOM")
		(9 "F.Adhes" user "F.Adhesive")
		(11 "B.Adhes" user "B.Adhesive")
		(13 "F.Paste" user "Package Geometry/Pastemask Top")
		(15 "B.Paste" user "Package Geometry/Pastemask Bottom")
		(5 "F.SilkS" user "Ref Des/Silkscreen Top")
		(7 "B.SilkS" user "Ref Des/Silkscreen Bottom")
		(1 "F.Mask" user "Board Geometry/Soldermask Top")
		(3 "B.Mask" user "Board Geometry/Soldermask Bottom")
		(17 "Dwgs.User" user "User.Drawings")
		(19 "Cmts.User" user "User.Comments")
		(21 "Eco1.User" user "User.Eco1")
		(23 "Eco2.User" user "User.Eco2")
		(25 "Edge.Cuts" user "Board Geometry/Outline")
		(27 "Margin" user)
		(31 "F.CrtYd" user "Package Geometry/Place Bound Top")
		(29 "B.CrtYd" user "Package Geometry/Place Bound Bottom")
		(35 "F.Fab" user "Ref Des/Assembly Top")
		(33 "B.Fab" user "Ref Des/Assembly Bottom")
	)
	(footprint ""
		(layer "F.Cu")
		(at 97.028 -89.535 90)
		(property "Reference" "C9355"
			(at 0 0 90)
			(layer "F.SilkS")
			(hide yes)
			(effects
				(font
					(size 1.27 1.27)
				)
			)
		)
		(property "Value" "SC1KP50V2KX-1GP"
			(at 1.1811 -2.7051 90)
			(unlocked yes)
			(layer "F.Fab")
			(hide yes)
			(effects
				(font
					(size 1.016 1.016)
					(thickness 0.1524)
				)
			)
		)
		(property "Device Type" "C402H22"
			(at 1.1811 -4.2291 90)
			(unlocked yes)
			(layer "F.Fab")
			(hide yes)
			(effects
				(font
					(size 1.016 1.016)
					(thickness 0.1524)
				)
			)
		)
		(duplicate_pad_numbers_are_jumpers no)
		(fp_rect
			(start -0.4318 0.9525)
			(end 0.4318 -0.9525)
			(stroke
				(width 0)
				(type default)
			)
			(fill no)
			(layer "F.CrtYd")
		)
		(fp_rect
			(start -0.4318 0.9525)
			(end 0.4318 -0.9525)
			(stroke
				(width 0)
				(type default)
			)
			(fill no)
			(layer "F.Fab")
		)
		(pad "1" smd custom
			(at 0 -0.4445 90)
			(size 0.1524 0.1524)
			(layers "F.Cu" "F.Mask" "F.Paste")
			(net "SSD_PRSNT14")
			(options
				(clearance outline)
				(anchor circle)
			)
			(primitives
				(gr_poly
					(pts
						(arc
							(start 0.3048 -0.2032)
							(mid 0.275042 -0.275042)
							(end 0.2032 -0.3048)
						)
						(arc
							(start -0.2032 -0.3048)
							(mid -0.275042 -0.275042)
							(end -0.3048 -0.2032)
						)
						(arc
							(start -0.3048 0.2032)
							(mid -0.275042 0.275042)
							(end -0.2032 0.3048)
						)
						(arc
							(start 0.2032 0.3048)
							(mid 0.275042 0.275042)
							(end 0.3048 0.2032)
						)
					)
					(width 0)
					(fill yes)
				)
			)
		)
		(pad "2" smd custom
			(at 0 0.4445 90)
			(size 0.1524 0.1524)
			(layers "F.Cu" "F.Mask" "F.Paste")
			(net "GND")
			(options
				(clearance outline)
				(anchor circle)
			)
			(primitives
				(gr_poly
					(pts
						(arc
							(start 0.3048 -0.2032)
							(mid 0.275042 -0.275042)
							(end 0.2032 -0.3048)
						)
						(arc
							(start -0.2032 -0.3048)
							(mid -0.275042 -0.275042)
							(end -0.3048 -0.2032)
						)
						(arc
							(start -0.3048 0.2032)
							(mid -0.275042 0.275042)
							(end -0.2032 0.3048)
						)
						(arc
							(start 0.2032 0.3048)
							(mid 0.275042 0.275042)
							(end 0.3048 0.2032)
						)
					)
					(width 0)
					(fill yes)
				)
			)
		)
	)
	(footprint ""
		(layer "F.Cu")
		(at 50.546 -138.303 180)
		(property "Reference" "R344"
			(at 0 0 180)
			(layer "F.SilkS")
			(hide yes)
			(effects
				(font
					(size 1.27 1.27)
				)
			)
		)
		(property "Value" "4K7R2J-2-GP"
			(at 0.064008 -3.993896 180)
			(unlocked yes)
			(layer "F.Fab")
			(hide yes)
			(effects
				(font
					(size 1.016 1.016)
					(thickness 0.1524)
				)
			)
		)
		(property "Device Type" "R402H16"
			(at 0.064008 -5.517896 180)
			(unlocked yes)
			(layer "F.Fab")
			(hide yes)
			(effects
				(font
					(size 1.016 1.016)
					(thickness 0.1524)
				)
			)
		)
		(duplicate_pad_numbers_are_jumpers no)
		(fp_line
			(start 0.508 -0.9398)
			(end -0.508 -0.9398)
			(stroke
				(width 0.1524)
				(type default)
			)
			(layer "F.SilkS")
		)
		(fp_line
			(start -0.508 -0.9398)
			(end -0.508 0.9398)
			(stroke
				(width 0.1524)
				(type default)
			)
			(layer "F.SilkS")
		)
		(fp_rect
			(start -0.508 0.9398)
			(end 0.508 -0.9398)
			(stroke
				(width 0)
				(type default)
			)
			(fill no)
			(layer "F.CrtYd")
		)
		(fp_rect
			(start -0.508 0.9398)
			(end 0.508 -0.9398)
			(stroke
				(width 0)
				(type default)
			)
			(fill no)
			(layer "F.Fab")
		)
		(pad "1" smd custom
			(at 0 -0.4445 180)
			(size 0.1397 0.1397)
			(layers "F.Cu" "F.Mask" "F.Paste")
			(net "I2C_B_TMP1_A0")
			(options
				(clearance outline)
				(anchor circle)
			)
			(primitives
				(gr_poly
					(pts
						(arc
							(start -0.1778 -0.2794)
							(mid -0.249642 -0.249642)
							(end -0.2794 -0.1778)
						)
						(arc
							(start -0.2794 0.1778)
							(mid -0.249642 0.249642)
							(end -0.1778 0.2794)
						)
						(arc
							(start 0.1778 0.2794)
							(mid 0.249642 0.249642)
							(end 0.2794 0.1778)
						)
						(arc
							(start 0.2794 -0.1778)
							(mid 0.249642 -0.249642)
							(end 0.1778 -0.2794)
						)
					)
					(width 0)
					(fill yes)
				)
			)
		)
		(pad "2" smd custom
			(at 0 0.4445 180)
			(size 0.1397 0.1397)
			(layers "F.Cu" "F.Mask" "F.Paste")
			(net "GND")
			(options
				(clearance outline)
				(anchor circle)
			)
			(primitives
				(gr_poly
					(pts
						(arc
							(start -0.1778 -0.2794)
							(mid -0.249642 -0.249642)
							(end -0.2794 -0.1778)
						)
						(arc
							(start -0.2794 0.1778)
							(mid -0.249642 0.249642)
							(end -0.1778 0.2794)
						)
						(arc
							(start 0.1778 0.2794)
							(mid 0.249642 0.249642)
							(end 0.2794 0.1778)
						)
						(arc
							(start 0.2794 -0.1778)
							(mid 0.249642 -0.249642)
							(end 0.1778 -0.2794)
						)
					)
					(width 0)
					(fill yes)
				)
			)
		)
	)
	(footprint ""
		(layer "F.Cu")
		(at 91.313 -440.436 180)
		(property "Reference" "R9065"
			(at 0 0 180)
			(layer "F.SilkS")
			(hide yes)
			(effects
				(font
					(size 1.27 1.27)
				)
			)
		)
		(property "Value" "27R2F-GP"
			(at 0.064008 -3.993896 180)
			(unlocked yes)
			(layer "F.Fab")
			(hide yes)
			(effects
				(font
					(size 1.016 1.016)
					(thickness 0.1524)
				)
			)
		)
		(property "Device Type" "R402H16"
			(at 0.064008 -5.517896 180)
			(unlocked yes)
			(layer "F.Fab")
			(hide yes)
			(effects
				(font
					(size 1.016 1.016)
					(thickness 0.1524)
				)
			)
		)
		(duplicate_pad_numbers_are_jumpers no)
		(fp_line
			(start 0.508 -0.9398)
			(end -0.508 -0.9398)
			(stroke
				(width 0.1524)
				(type default)
			)
			(layer "F.SilkS")
		)
		(fp_line
			(start -0.508 -0.9398)
			(end -0.508 0.9398)
			(stroke
				(width 0.1524)
				(type default)
			)
			(layer "F.SilkS")
		)
		(fp_rect
			(start -0.508 0.9398)
			(end 0.508 -0.9398)
			(stroke
				(width 0)
				(type default)
			)
			(fill no)
			(layer "F.CrtYd")
		)
		(fp_rect
			(start -0.508 0.9398)
			(end 0.508 -0.9398)
			(stroke
				(width 0)
				(type default)
			)
			(fill no)
			(layer "F.Fab")
		)
		(pad "1" smd custom
			(at 0 -0.4445 180)
			(size 0.1397 0.1397)
			(layers "F.Cu" "F.Mask" "F.Paste")
			(net "PE_CLK_100M_DR5_2_R_P")
			(options
				(clearance outline)
				(anchor circle)
			)
			(primitives
				(gr_poly
					(pts
						(arc
							(start -0.1778 -0.2794)
							(mid -0.249642 -0.249642)
							(end -0.2794 -0.1778)
						)
						(arc
							(start -0.2794 0.1778)
							(mid -0.249642 0.249642)
							(end -0.1778 0.2794)
						)
						(arc
							(start 0.1778 0.2794)
							(mid 0.249642 0.249642)
							(end 0.2794 0.1778)
						)
						(arc
							(start 0.2794 -0.1778)
							(mid 0.249642 -0.249642)
							(end 0.1778 -0.2794)
						)
					)
					(width 0)
					(fill yes)
				)
			)
		)
		(pad "2" smd custom
			(at 0 0.4445 180)
			(size 0.1397 0.1397)
			(layers "F.Cu" "F.Mask" "F.Paste")
			(net "PE_CLK100M_DR5_2_P")
			(options
				(clearance outline)
				(anchor circle)
			)
			(primitives
				(gr_poly
					(pts
						(arc
							(start -0.1778 -0.2794)
							(mid -0.249642 -0.249642)
							(end -0.2794 -0.1778)
						)
						(arc
							(start -0.2794 0.1778)
							(mid -0.249642 0.249642)
							(end -0.1778 0.2794)
						)
						(arc
							(start 0.1778 0.2794)
							(mid 0.249642 0.249642)
							(end 0.2794 0.1778)
						)
						(arc
							(start 0.2794 -0.1778)
							(mid 0.249642 -0.249642)
							(end 0.1778 -0.2794)
						)
					)
					(width 0)
					(fill yes)
				)
			)
		)
	)
	(footprint ""
		(layer "F.Cu")
		(at 50.546 -134.493 180)
		(property "Reference" "R343"
			(at 0 0 180)
			(layer "F.SilkS")
			(hide yes)
			(effects
				(font
					(size 1.27 1.27)
				)
			)
		)
		(property "Value" "4K7R2J-2-GP"
			(at 0.064008 -3.993896 180)
			(unlocked yes)
			(layer "F.Fab")
			(hide yes)
			(effects
				(font
					(size 1.016 1.016)
					(thickness 0.1524)
				)
			)
		)
		(property "Device Type" "R402H16"
			(at 0.064008 -5.517896 180)
			(unlocked yes)
			(layer "F.Fab")
			(hide yes)
			(effects
				(font
					(size 1.016 1.016)
					(thickness 0.1524)
				)
			)
		)
		(duplicate_pad_numbers_are_jumpers no)
		(fp_line
			(start 0.508 -0.9398)
			(end -0.508 -0.9398)
			(stroke
				(width 0.1524)
				(type default)
			)
			(layer "F.SilkS")
		)
		(fp_line
			(start -0.508 -0.9398)
			(end -0.508 0.9398)
			(stroke
				(width 0.1524)
				(type default)
			)
			(layer "F.SilkS")
		)
		(fp_rect
			(start -0.508 0.9398)
			(end 0.508 -0.9398)
			(stroke
				(width 0)
				(type default)
			)
			(fill no)
			(layer "F.CrtYd")
		)
		(fp_rect
			(start -0.508 0.9398)
			(end 0.508 -0.9398)
			(stroke
				(width 0)
				(type default)
			)
			(fill no)
			(layer "F.Fab")
		)
		(pad "1" smd custom
			(at 0 -0.4445 180)
			(size 0.1397 0.1397)
			(layers "F.Cu" "F.Mask" "F.Paste")
			(net "I2C_B_TMP1_A2")
			(options
				(clearance outline)
				(anchor circle)
			)
			(primitives
				(gr_poly
					(pts
						(arc
							(start -0.1778 -0.2794)
							(mid -0.249642 -0.249642)
							(end -0.2794 -0.1778)
						)
						(arc
							(start -0.2794 0.1778)
							(mid -0.249642 0.249642)
							(end -0.1778 0.2794)
						)
						(arc
							(start 0.1778 0.2794)
							(mid 0.249642 0.249642)
							(end 0.2794 0.1778)
						)
						(arc
							(start 0.2794 -0.1778)
							(mid 0.249642 -0.249642)
							(end 0.1778 -0.2794)
						)
					)
					(width 0)
					(fill yes)
				)
			)
		)
		(pad "2" smd custom
			(at 0 0.4445 180)
			(size 0.1397 0.1397)
			(layers "F.Cu" "F.Mask" "F.Paste")
			(net "GND")
			(options
				(clearance outline)
				(anchor circle)
			)
			(primitives
				(gr_poly
					(pts
						(arc
							(start -0.1778 -0.2794)
							(mid -0.249642 -0.249642)
							(end -0.2794 -0.1778)
						)
						(arc
							(start -0.2794 0.1778)
							(mid -0.249642 0.249642)
							(end -0.1778 0.2794)
						)
						(arc
							(start 0.1778 0.2794)
							(mid 0.249642 0.249642)
							(end 0.2794 0.1778)
						)
						(arc
							(start 0.2794 -0.1778)
							(mid 0.249642 -0.249642)
							(end 0.1778 -0.2794)
						)
					)
					(width 0)
					(fill yes)
				)
			)
		)
	)
	(footprint ""
		(layer "F.Cu")
		(at 88.138 -445.262)
		(property "Reference" "R9599"
			(at 0 0 0)
			(layer "F.SilkS")
			(hide yes)
			(effects
				(font
					(size 1.27 1.27)
				)
			)
		)
		(property "Value" "10R2F-L-GP"
			(at 0.064008 -3.993896 0)
			(unlocked yes)
			(layer "F.Fab")
			(hide yes)
			(effects
				(font
					(size 1.016 1.016)
					(thickness 0.1524)
				)
			)
		)
		(property "Device Type" "R402H14"
			(at 0.064008 -5.517896 0)
			(unlocked yes)
			(layer "F.Fab")
			(hide yes)
			(effects
				(font
					(size 1.016 1.016)
					(thickness 0.1524)
				)
			)
		)
		(duplicate_pad_numbers_are_jumpers no)
		(fp_line
			(start -0.508 -0.9398)
			(end -0.508 0.9398)
			(stroke
				(width 0.1524)
				(type default)
			)
			(layer "F.SilkS")
		)
		(fp_line
			(start 0.508 -0.9398)
			(end -0.508 -0.9398)
			(stroke
				(width 0.1524)
				(type default)
			)
			(layer "F.SilkS")
		)
		(fp_rect
			(start -0.508 0.9398)
			(end 0.508 -0.9398)
			(stroke
				(width 0)
				(type default)
			)
			(fill no)
			(layer "F.CrtYd")
		)
		(fp_rect
			(start -0.508 0.9398)
			(end 0.508 -0.9398)
			(stroke
				(width 0)
				(type default)
			)
			(fill no)
			(layer "F.Fab")
		)
		(pad "1" smd custom
			(at 0 -0.4445)
			(size 0.1397 0.1397)
			(layers "F.Cu" "F.Mask" "F.Paste")
			(net "SSD5_CLK0_OE_N")
			(options
				(clearance outline)
				(anchor circle)
			)
			(primitives
				(gr_poly
					(pts
						(arc
							(start -0.1778 -0.2794)
							(mid -0.249642 -0.249642)
							(end -0.2794 -0.1778)
						)
						(arc
							(start -0.2794 0.1778)
							(mid -0.249642 0.249642)
							(end -0.1778 0.2794)
						)
						(arc
							(start 0.1778 0.2794)
							(mid 0.249642 0.249642)
							(end 0.2794 0.1778)
						)
						(arc
							(start 0.2794 -0.1778)
							(mid 0.249642 -0.249642)
							(end 0.1778 -0.2794)
						)
					)
					(width 0)
					(fill yes)
				)
			)
		)
		(pad "2" smd custom
			(at 0 0.4445)
			(size 0.1397 0.1397)
			(layers "F.Cu" "F.Mask" "F.Paste")
			(net "SSD5_CLK0_OE_R_N")
			(options
				(clearance outline)
				(anchor circle)
			)
			(primitives
				(gr_poly
					(pts
						(arc
							(start -0.1778 -0.2794)
							(mid -0.249642 -0.249642)
							(end -0.2794 -0.1778)
						)
						(arc
							(start -0.2794 0.1778)
							(mid -0.249642 0.249642)
							(end -0.1778 0.2794)
						)
						(arc
							(start 0.1778 0.2794)
							(mid 0.249642 0.249642)
							(end 0.2794 0.1778)
						)
						(arc
							(start 0.2794 -0.1778)
							(mid 0.249642 -0.249642)
							(end 0.1778 -0.2794)
						)
					)
					(width 0)
					(fill yes)
				)
			)
		)
	)
	(footprint ""
		(layer "F.Cu")
		(at 47.879 -349.885 -90)
		(property "Reference" "R9471"
			(at 0 0 270)
			(layer "F.SilkS")
			(hide yes)
			(effects
				(font
					(size 1.27 1.27)
				)
			)
		)
		(property "Value" "100R2J-2-GP"
			(at 0.064008 -3.993896 270)
			(unlocked yes)
			(layer "F.Fab")
			(hide yes)
			(effects
				(font
					(size 1.016 1.016)
					(thickness 0.1524)
				)
			)
		)
		(property "Device Type" "R402H14"
			(at 0.064008 -5.517896 270)
			(unlocked yes)
			(layer "F.Fab")
			(hide yes)
			(effects
				(font
					(size 1.016 1.016)
					(thickness 0.1524)
				)
			)
		)
		(duplicate_pad_numbers_are_jumpers no)
		(fp_line
			(start -0.508 -0.9398)
			(end -0.508 0.9398)
			(stroke
				(width 0.1524)
				(type default)
			)
			(layer "F.SilkS")
		)
		(fp_line
			(start 0.508 -0.9398)
			(end -0.508 -0.9398)
			(stroke
				(width 0.1524)
				(type default)
			)
			(layer "F.SilkS")
		)
		(fp_rect
			(start -0.508 0.9398)
			(end 0.508 -0.9398)
			(stroke
				(width 0)
				(type default)
			)
			(fill no)
			(layer "F.CrtYd")
		)
		(fp_rect
			(start -0.508 0.9398)
			(end 0.508 -0.9398)
			(stroke
				(width 0)
				(type default)
			)
			(fill no)
			(layer "F.Fab")
		)
		(pad "1" smd custom
			(at 0 -0.4445 270)
			(size 0.1397 0.1397)
			(layers "F.Cu" "F.Mask" "F.Paste")
			(net "P3V3")
			(options
				(clearance outline)
				(anchor circle)
			)
			(primitives
				(gr_poly
					(pts
						(arc
							(start -0.1778 -0.2794)
							(mid -0.249642 -0.249642)
							(end -0.2794 -0.1778)
						)
						(arc
							(start -0.2794 0.1778)
							(mid -0.249642 0.249642)
							(end -0.1778 0.2794)
						)
						(arc
							(start 0.1778 0.2794)
							(mid 0.249642 0.249642)
							(end 0.2794 0.1778)
						)
						(arc
							(start 0.2794 -0.1778)
							(mid 0.249642 -0.249642)
							(end 0.1778 -0.2794)
						)
					)
					(width 0)
					(fill yes)
				)
			)
		)
		(pad "2" smd custom
			(at 0 0.4445 270)
			(size 0.1397 0.1397)
			(layers "F.Cu" "F.Mask" "F.Paste")
			(net "DRV_ACT_6")
			(options
				(clearance outline)
				(anchor circle)
			)
			(primitives
				(gr_poly
					(pts
						(arc
							(start -0.1778 -0.2794)
							(mid -0.249642 -0.249642)
							(end -0.2794 -0.1778)
						)
						(arc
							(start -0.2794 0.1778)
							(mid -0.249642 0.249642)
							(end -0.1778 0.2794)
						)
						(arc
							(start 0.1778 0.2794)
							(mid 0.249642 0.249642)
							(end 0.2794 0.1778)
						)
						(arc
							(start 0.2794 -0.1778)
							(mid 0.249642 -0.249642)
							(end 0.1778 -0.2794)
						)
					)
					(width 0)
					(fill yes)
				)
			)
		)
	)
	(footprint ""
		(layer "F.Cu")
		(at 23.998174 -165.08349 -90)
		(property "Reference" "U210"
			(at 0 0 270)
			(layer "F.SilkS")
			(hide yes)
			(effects
				(font
					(size 1.27 1.27)
				)
			)
		)
		(property "Value" "SN74LVC1G08DCKR-GP"
			(at -2.3368 -8.6868 270)
			(unlocked yes)
			(layer "F.Fab")
			(hide yes)
			(effects
				(font
					(size 1.016 1.016)
					(thickness 0.1524)
				)
			)
		)
		(property "Device Type" "SC70-5H44"
			(at -2.3114 -10.414 270)
			(unlocked yes)
			(layer "F.Fab")
			(hide yes)
			(effects
				(font
					(size 1.016 1.016)
					(thickness 0.1524)
				)
			)
		)
		(duplicate_pad_numbers_are_jumpers no)
		(fp_line
			(start -1.27 1.7018)
			(end -1.27 -1.7018)
			(stroke
				(width 0.1524)
				(type default)
			)
			(layer "F.SilkS")
		)
		(fp_line
			(start 1.27 1.7018)
			(end -1.27 1.7018)
			(stroke
				(width 0.1524)
				(type default)
			)
			(layer "F.SilkS")
		)
		(fp_line
			(start -1.27 -1.7018)
			(end 1.27 -1.7018)
			(stroke
				(width 0.1524)
				(type default)
			)
			(layer "F.SilkS")
		)
		(fp_line
			(start 1.27 -1.7018)
			(end 1.27 1.7018)
			(stroke
				(width 0.1524)
				(type default)
			)
			(layer "F.SilkS")
		)
		(fp_line
			(start 0.6604 -1.8034)
			(end 1.3843 -1.8034)
			(stroke
				(width 0.3302)
				(type default)
			)
			(layer "F.SilkS")
		)
		(fp_line
			(start 1.3843 -1.8034)
			(end 1.3843 -1.1176)
			(stroke
				(width 0.3302)
				(type default)
			)
			(layer "F.SilkS")
		)
		(fp_rect
			(start -1.524 1.9558)
			(end 1.524 -1.9558)
			(stroke
				(width 0)
				(type default)
			)
			(fill no)
			(layer "F.CrtYd")
		)
		(fp_poly
			(pts
				(xy -1.524 -1.9558) (xy 1.524 -1.9558) (xy 1.524 1.9558) (xy -1.524 1.9558)
			)
			(stroke
				(width 0)
				(type default)
			)
			(fill no)
			(layer "F.Fab")
		)
		(pad "1" smd rect
			(at 0.65024 -0.8255 270)
			(size 0.4064 1.2192)
			(layers "F.Cu" "F.Mask" "F.Paste")
			(net "SSD13_CLK0_OE_MOS_N")
		)
		(pad "2" smd rect
			(at 0 -0.8255 270)
			(size 0.4064 1.2192)
			(layers "F.Cu" "F.Mask" "F.Paste")
			(net "ATTN_LED_DR13_N")
		)
		(pad "3" smd rect
			(at -0.65024 -0.8255 270)
			(size 0.4064 1.2192)
			(layers "F.Cu" "F.Mask" "F.Paste")
			(net "GND")
		)
		(pad "4" smd rect
			(at -0.65024 0.8255 270)
			(size 0.4064 1.2192)
			(layers "F.Cu" "F.Mask" "F.Paste")
			(net "ATTN_LED_DR13_AND")
		)
		(pad "5" smd rect
			(at 0.65024 0.8255 270)
			(size 0.4064 1.2192)
			(layers "F.Cu" "F.Mask" "F.Paste")
			(net "P3V3")
		)
	)
)
